# S9S_MB_2U (Grand Teton) — schematic netlist excerpt (pin names and nets, part order shuffled) for the footprints in the layout excerpt that follows; sources: Cadence DE-HDL packaged netlist, KiCad conversion of 03242023_DA0F0TMBIJ0_F0T_Motherboard_J_brd_V01_OCP.brd

PU297  MP5991GLUZ  MP5991GLU-Z IC  pkg LGA32_TH_0-5_5X5  page 303
  VOUT1  = P12V_AUX
  VOUT2  = P12V_AUX
  D_OC  = HSC_D_OC_4
  \on\  = HSC_ON
  GOK  = HSC_FAULT
  FLT_TYPE  = HSC_FLT_TYPE_4
  NC1  = HSC_NC1_4
  MODE  = HSC_MODE_4
  VIN1  = P12V_PSU
  VIN2  = P12V_PSU
  VIN3  = P12V_PSU
  VIN4  = P12V_PSU
  VIN5  = P12V_PSU
  VIN6  = P12V_PSU
  VIN7  = P12V_PSU
  VIN8  = P12V_PSU
  SCREF_OCWREF  = HSC_SCREF_4
  VTEMP  = HSC_VTEMP
  SS  = HSC_SS
  GND  = AGND_HSC
  VDD33  = HSC_VDD_R_4
  IMON  = HSC_IMON
  CS  = HSC_CS_4
  OCREF  = HSC_OCREF
  VOUT3  = P12V_AUX
  VOUT4  = P12V_AUX
  VOUT5  = P12V_AUX
  VOUT6  = P12V_AUX
  VOUT7  = P12V_AUX
  VOUT8  = P12V_AUX
  VOUT9  = P12V_AUX
  VOUT10  = P12V_AUX
  VIN9  = P12V_PSU

(kicad_pcb
	(version 20260206)
	(generator "pcbnew")
	(generator_version "10.0")
	(general
		(thickness 1.6)
		(legacy_teardrops no)
	)
	(paper "A4")
	(title_block
		(title "03242023_DA0F0TMBIJ0_F0T_Motherboard_J_brd_V01_OCP.brd")
		(comment 1 "Grand Teton / footprints 3729-3729 of 6105")
	)
	(layers
		(0 "F.Cu" signal "TOP")
		(4 "In1.Cu" signal "GND")
		(6 "In2.Cu" signal "IN1")
		(8 "In3.Cu" signal "GND1")
		(10 "In4.Cu" signal "IN2")
		(12 "In5.Cu" signal "GND2")
		(14 "In6.Cu" signal "IN3")
		(16 "In7.Cu" signal "GND3")
		(18 "In8.Cu" signal "VCC")
		(20 "In9.Cu" signal "VCC1")
		(22 "In10.Cu" signal "GND4")
		(24 "In11.Cu" signal "IN4")
		(26 "In12.Cu" signal "GND5")
		(28 "In13.Cu" signal "IN5")
		(30 "In14.Cu" signal "GND6")
		(32 "In15.Cu" signal "IN6")
		(34 "In16.Cu" signal "GND7")
		(2 "B.Cu" signal "BOTTOM")
		(9 "F.Adhes" user "F.Adhesive")
		(11 "B.Adhes" user "B.Adhesive")
		(13 "F.Paste" user "Package Geometry/Pastemask Top")
		(15 "B.Paste" user "Package Geometry/Pastemask Bottom")
		(5 "F.SilkS" user "Ref Des/Silkscreen Top")
		(7 "B.SilkS" user "Ref Des/Silkscreen Bottom")
		(1 "F.Mask" user "Board Geometry/Soldermask Top")
		(3 "B.Mask" user "Board Geometry/Soldermask Bottom")
		(17 "Dwgs.User" user "User.Drawings")
		(19 "Cmts.User" user "User.Comments")
		(21 "Eco1.User" user "User.Eco1")
		(23 "Eco2.User" user "User.Eco2")
		(25 "Edge.Cuts" user "Board Geometry/Outline")
		(27 "Margin" user)
		(31 "F.CrtYd" user "Package Geometry/Place Bound Top")
		(29 "B.CrtYd" user "Package Geometry/Place Bound Bottom")
		(35 "F.Fab" user "Ref Des/Assembly Top")
		(33 "B.Fab" user "Ref Des/Assembly Bottom")
	)
	(footprint ""
		(layer "F.Cu")
		(at 232.176066 -402.722842 180)
		(property "Reference" "PU297"
			(at 0.384556 7.701788 0)
			(unlocked yes)
			(layer "F.SilkS")
			(effects
				(font
					(size 0.7874 0.5842)
					(thickness 0.1524)
				)
			)
		)
		(property "Value" ""
			(at 0 0 180)
			(layer "F.Fab")
			(effects
				(font
					(size 1.27 1.27)
				)
			)
		)
		(duplicate_pad_numbers_are_jumpers no)
		(fp_line
			(start 2.567686 2.567686)
			(end 2.567686 -2.567686)
			(stroke
				(width 0.1524)
				(type default)
			)
			(layer "F.SilkS")
		)
		(fp_line
			(start 2.567686 -2.567686)
			(end -2.567686 -2.567686)
			(stroke
				(width 0.1524)
				(type default)
			)
			(layer "F.SilkS")
		)
		(fp_line
			(start -2.567686 2.567686)
			(end 2.567686 2.567686)
			(stroke
				(width 0.1524)
				(type default)
			)
			(layer "F.SilkS")
		)
		(fp_line
			(start -2.567686 -2.567686)
			(end -2.567686 2.567686)
			(stroke
				(width 0.1524)
				(type default)
			)
			(layer "F.SilkS")
		)
		(fp_poly
			(pts
				(xy -3.429 -3.101594) (xy -3.06959 -2.024126) (xy -4.147312 -2.383282)
			)
			(stroke
				(width 0)
				(type default)
			)
			(fill yes)
			(layer "F.SilkS")
		)
		(fp_line
			(start 2.549906 2.549906)
			(end 2.549906 -2.549906)
			(stroke
				(width 0.1)
				(type default)
			)
			(layer "F.Fab")
		)
		(fp_line
			(start 2.549906 -2.549906)
			(end -2.549906 -2.549906)
			(stroke
				(width 0.1)
				(type default)
			)
			(layer "F.Fab")
		)
		(fp_line
			(start -2.549906 2.549906)
			(end 2.549906 2.549906)
			(stroke
				(width 0.1)
				(type default)
			)
			(layer "F.Fab")
		)
		(fp_line
			(start -2.549906 -2.549906)
			(end -2.549906 2.549906)
			(stroke
				(width 0.1)
				(type default)
			)
			(layer "F.Fab")
		)
		(fp_poly
			(pts
				(xy -3.806698 -2.25806) (xy -3.806698 -1.24206) (xy -2.790698 -1.75006)
			)
			(stroke
				(width 0)
				(type default)
			)
			(fill yes)
			(layer "F.Fab")
		)
		(pad "1" smd rect
			(at -2.250186 -1.75006 270)
			(size 0.254 0.3556)
			(layers "F.Cu" "F.Mask" "F.Paste")
			(net "P12V_AUX")
		)
		(pad "2" smd rect
			(at -2.237486 -1.249934 270)
			(size 0.254 0.381)
			(layers "F.Cu" "F.Mask" "F.Paste")
			(net "P12V_AUX")
		)
		(pad "3" smd rect
			(at -2.237486 -0.750062 270)
			(size 0.254 0.381)
			(layers "F.Cu" "F.Mask" "F.Paste")
			(net "HSC_D_OC_4")
		)
		(pad "4" smd rect
			(at -2.237486 -0.249936 270)
			(size 0.254 0.381)
			(layers "F.Cu" "F.Mask" "F.Paste")
			(net "HSC_ON")
		)
		(pad "5" smd rect
			(at -2.237486 0.249936 270)
			(size 0.254 0.381)
			(layers "F.Cu" "F.Mask" "F.Paste")
			(net "HSC_FAULT")
		)
		(pad "6" smd rect
			(at -2.237486 0.750062 270)
			(size 0.254 0.381)
			(layers "F.Cu" "F.Mask" "F.Paste")
			(net "HSC_FLT_TYPE_4")
		)
		(pad "7" smd rect
			(at -2.237486 1.249934 270)
			(size 0.254 0.381)
			(layers "F.Cu" "F.Mask" "F.Paste")
			(net "HSC_NC1_4")
		)
		(pad "8" smd rect
			(at -2.250186 1.75006 270)
			(size 0.254 0.3556)
			(layers "F.Cu" "F.Mask" "F.Paste")
			(net "HSC_MODE_4")
		)
		(pad "9" smd rect
			(at -1.75006 2.250186 180)
			(size 0.254 0.3556)
			(layers "F.Cu" "F.Mask" "F.Paste")
			(net "P12V_PSU")
		)
		(pad "10" smd rect
			(at -1.249934 2.237486 180)
			(size 0.254 0.381)
			(layers "F.Cu" "F.Mask" "F.Paste")
			(net "P12V_PSU")
		)
		(pad "11" smd rect
			(at -0.750062 2.237486 180)
			(size 0.254 0.381)
			(layers "F.Cu" "F.Mask" "F.Paste")
			(net "P12V_PSU")
		)
		(pad "12" smd rect
			(at -0.249936 2.237486 180)
			(size 0.254 0.381)
			(layers "F.Cu" "F.Mask" "F.Paste")
			(net "P12V_PSU")
		)
		(pad "13" smd rect
			(at 0.249936 2.237486 180)
			(size 0.254 0.381)
			(layers "F.Cu" "F.Mask" "F.Paste")
			(net "P12V_PSU")
		)
		(pad "14" smd rect
			(at 0.750062 2.237486 180)
			(size 0.254 0.381)
			(layers "F.Cu" "F.Mask" "F.Paste")
			(net "P12V_PSU")
		)
		(pad "15" smd rect
			(at 1.249934 2.237486 180)
			(size 0.254 0.381)
			(layers "F.Cu" "F.Mask" "F.Paste")
			(net "P12V_PSU")
		)
		(pad "16" smd rect
			(at 1.75006 2.250186 180)
			(size 0.254 0.3556)
			(layers "F.Cu" "F.Mask" "F.Paste")
			(net "P12V_PSU")
		)
		(pad "17" smd rect
			(at 2.250186 1.75006 270)
			(size 0.254 0.3556)
			(layers "F.Cu" "F.Mask" "F.Paste")
			(net "HSC_SCREF_4")
		)
		(pad "18" smd rect
			(at 2.237486 1.249934 270)
			(size 0.254 0.381)
			(layers "F.Cu" "F.Mask" "F.Paste")
			(net "HSC_VTEMP")
		)
		(pad "19" smd rect
			(at 2.237486 0.750062 270)
			(size 0.254 0.381)
			(layers "F.Cu" "F.Mask" "F.Paste")
			(net "HSC_SS")
		)
		(pad "20" smd rect
			(at 2.237486 0.249936 270)
			(size 0.254 0.381)
			(layers "F.Cu" "F.Mask" "F.Paste")
			(net "AGND_HSC")
		)
		(pad "21" smd rect
			(at 2.237486 -0.249936 270)
			(size 0.254 0.381)
			(layers "F.Cu" "F.Mask" "F.Paste")
			(net "HSC_VDD_R_4")
		)
		(pad "22" smd rect
			(at 2.237486 -0.750062 270)
			(size 0.254 0.381)
			(layers "F.Cu" "F.Mask" "F.Paste")
			(net "HSC_IMON")
		)
		(pad "23" smd rect
			(at 2.237486 -1.249934 270)
			(size 0.254 0.381)
			(layers "F.Cu" "F.Mask" "F.Paste")
			(net "HSC_CS_4")
		)
		(pad "24" smd rect
			(at 2.250186 -1.75006 270)
			(size 0.254 0.3556)
			(layers "F.Cu" "F.Mask" "F.Paste")
			(net "HSC_OCREF")
		)
		(pad "25" smd rect
			(at 1.75006 -2.250186 180)
			(size 0.254 0.3556)
			(layers "F.Cu" "F.Mask" "F.Paste")
			(net "P12V_AUX")
		)
		(pad "26" smd rect
			(at 1.249934 -2.237486 180)
			(size 0.254 0.381)
			(layers "F.Cu" "F.Mask" "F.Paste")
			(net "P12V_AUX")
		)
		(pad "27" smd rect
			(at 0.750062 -2.237486 180)
			(size 0.254 0.381)
			(layers "F.Cu" "F.Mask" "F.Paste")
			(net "P12V_AUX")
		)
		(pad "28" smd rect
			(at 0.249936 -2.237486 180)
			(size 0.254 0.381)
			(layers "F.Cu" "F.Mask" "F.Paste")
			(net "P12V_AUX")
		)
		(pad "29" smd rect
			(at -0.249936 -2.237486 180)
			(size 0.254 0.381)
			(layers "F.Cu" "F.Mask" "F.Paste")
			(net "P12V_AUX")
		)
		(pad "30" smd rect
			(at -0.750062 -2.237486 180)
			(size 0.254 0.381)
			(layers "F.Cu" "F.Mask" "F.Paste")
			(net "P12V_AUX")
		)
		(pad "31" smd rect
			(at -1.249934 -2.237486 180)
			(size 0.254 0.381)
			(layers "F.Cu" "F.Mask" "F.Paste")
			(net "P12V_AUX")
		)
		(pad "32" smd rect
			(at -1.75006 -2.250186 180)
			(size 0.254 0.3556)
			(layers "F.Cu" "F.Mask" "F.Paste")
			(net "P12V_AUX")
		)
		(pad "33" smd rect
			(at 0 0 180)
			(size 3.4036 3.4036)
			(layers "F.Cu" "F.Mask" "F.Paste")
			(net "P12V_PSU")
		)
		(zone
			(layer "F.Cu")
			(hatch none 0.5)
			(connect_pads
				(clearance 0)
			)
			(min_thickness 0.25)
			(keepout
				(tracks not_allowed)
				(vias allowed)
				(pads allowed)
				(copperpour not_allowed)
				(footprints allowed)
			)
			(placement
				(enabled no)
				(sheetname "")
			)
			(fill
				(thermal_gap 0.5)
				(thermal_bridge_width 0.5)
				(island_removal_mode 0)
			)
			(polygon
				(pts
					(xy 234.197652 -401.275042) (xy 234.197652 -400.825208) (xy 234.0737 -400.701256) (xy 233.623866 -400.701256)
					(xy 233.623866 -400.726656) (xy 230.728266 -400.726656) (xy 230.728266 -400.701256) (xy 230.15448 -400.701256)
					(xy 230.15448 -401.275042) (xy 230.17988 -401.275042) (xy 230.17988 -404.170642) (xy 230.15448 -404.170642)
					(xy 230.15448 -404.475442) (xy 230.423466 -404.475442) (xy 230.423466 -400.970242) (xy 233.928666 -400.970242)
					(xy 233.928666 -403.230842) (xy 234.172252 -403.230842) (xy 234.172252 -401.275042)
				)
			)
		)
	)
)
